# S9S_MB_2U (Grand Teton) — schematic netlist excerpt (pin names and nets, part order shuffled) for the footprints in the layout excerpt that follows; sources: Cadence DE-HDL packaged netlist, KiCad conversion of 03242023_DA0F0TMBIJ0_F0T_Motherboard_J_brd_V01_OCP.brd

R2922  Q_RES  0 5% CHIP  pkg 0402LF  page 227 : A = RST_SMB_SWITCH_N ; B = PU_RST_SMB_U181_N
R3177  Q_RES  0 5% CHIP  pkg 0402LF  page 159 : A = USB2_5_R1_DN ; B = USB2_5_DN

(kicad_pcb
	(version 20260206)
	(generator "pcbnew")
	(generator_version "10.0")
	(general
		(thickness 1.6)
		(legacy_teardrops no)
	)
	(paper "A4")
	(title_block
		(title "03242023_DA0F0TMBIJ0_F0T_Motherboard_J_brd_V01_OCP.brd")
		(comment 1 "Grand Teton / footprints 3609-3610 of 6105")
	)
	(layers
		(0 "F.Cu" signal "TOP")
		(4 "In1.Cu" signal "GND")
		(6 "In2.Cu" signal "IN1")
		(8 "In3.Cu" signal "GND1")
		(10 "In4.Cu" signal "IN2")
		(12 "In5.Cu" signal "GND2")
		(14 "In6.Cu" signal "IN3")
		(16 "In7.Cu" signal "GND3")
		(18 "In8.Cu" signal "VCC")
		(20 "In9.Cu" signal "VCC1")
		(22 "In10.Cu" signal "GND4")
		(24 "In11.Cu" signal "IN4")
		(26 "In12.Cu" signal "GND5")
		(28 "In13.Cu" signal "IN5")
		(30 "In14.Cu" signal "GND6")
		(32 "In15.Cu" signal "IN6")
		(34 "In16.Cu" signal "GND7")
		(2 "B.Cu" signal "BOTTOM")
		(9 "F.Adhes" user "F.Adhesive")
		(11 "B.Adhes" user "B.Adhesive")
		(13 "F.Paste" user "Package Geometry/Pastemask Top")
		(15 "B.Paste" user "Package Geometry/Pastemask Bottom")
		(5 "F.SilkS" user "Ref Des/Silkscreen Top")
		(7 "B.SilkS" user "Ref Des/Silkscreen Bottom")
		(1 "F.Mask" user "Board Geometry/Soldermask Top")
		(3 "B.Mask" user "Board Geometry/Soldermask Bottom")
		(17 "Dwgs.User" user "User.Drawings")
		(19 "Cmts.User" user "User.Comments")
		(21 "Eco1.User" user "User.Eco1")
		(23 "Eco2.User" user "User.Eco2")
		(25 "Edge.Cuts" user "Board Geometry/Outline")
		(27 "Margin" user)
		(31 "F.CrtYd" user "Package Geometry/Place Bound Top")
		(29 "B.CrtYd" user "Package Geometry/Place Bound Bottom")
		(35 "F.Fab" user "Ref Des/Assembly Top")
		(33 "B.Fab" user "Ref Des/Assembly Bottom")
	)
	(footprint ""
		(layer "F.Cu")
		(at 12.778232 -15.320518 90)
		(property "Reference" "R3177"
			(at 0 0 90)
			(layer "F.SilkS")
			(hide yes)
			(effects
				(font
					(size 1.27 1.27)
				)
			)
		)
		(property "Value" ""
			(at 0 0 90)
			(layer "F.Fab")
			(effects
				(font
					(size 1.27 1.27)
				)
			)
		)
		(duplicate_pad_numbers_are_jumpers no)
		(fp_line
			(start 0.7874 -0.4064)
			(end 0.7874 0.4064)
			(stroke
				(width 0.1524)
				(type default)
			)
			(layer "F.SilkS")
		)
		(fp_line
			(start -0.7874 -0.4064)
			(end 0.7874 -0.4064)
			(stroke
				(width 0.1524)
				(type default)
			)
			(layer "F.SilkS")
		)
		(fp_line
			(start 0.7874 0.4064)
			(end -0.7874 0.4064)
			(stroke
				(width 0.1524)
				(type default)
			)
			(layer "F.SilkS")
		)
		(fp_line
			(start -0.7874 0.4064)
			(end -0.7874 -0.4064)
			(stroke
				(width 0.1524)
				(type default)
			)
			(layer "F.SilkS")
		)
		(fp_line
			(start -0.12065 -0.305054)
			(end -0.12065 -0.2794)
			(stroke
				(width 0.1)
				(type default)
			)
			(layer "F.Fab")
		)
		(fp_line
			(start -0.67945 -0.305054)
			(end -0.12065 -0.305054)
			(stroke
				(width 0.1)
				(type default)
			)
			(layer "F.Fab")
		)
		(fp_line
			(start 0.67945 -0.3048)
			(end 0.67945 0.3048)
			(stroke
				(width 0.1)
				(type default)
			)
			(layer "F.Fab")
		)
		(fp_line
			(start 0.12065 -0.3048)
			(end 0.67945 -0.3048)
			(stroke
				(width 0.1)
				(type default)
			)
			(layer "F.Fab")
		)
		(fp_line
			(start 0.12065 -0.2794)
			(end 0.12065 -0.3048)
			(stroke
				(width 0.1)
				(type default)
			)
			(layer "F.Fab")
		)
		(fp_line
			(start -0.12065 -0.2794)
			(end 0.12065 -0.2794)
			(stroke
				(width 0.1)
				(type default)
			)
			(layer "F.Fab")
		)
		(fp_line
			(start 0.120396 0.2794)
			(end -0.12065 0.2794)
			(stroke
				(width 0.1)
				(type default)
			)
			(layer "F.Fab")
		)
		(fp_line
			(start -0.12065 0.2794)
			(end -0.12065 0.3048)
			(stroke
				(width 0.1)
				(type default)
			)
			(layer "F.Fab")
		)
		(fp_line
			(start 0.67945 0.3048)
			(end 0.120396 0.3048)
			(stroke
				(width 0.1)
				(type default)
			)
			(layer "F.Fab")
		)
		(fp_line
			(start 0.120396 0.3048)
			(end 0.120396 0.2794)
			(stroke
				(width 0.1)
				(type default)
			)
			(layer "F.Fab")
		)
		(fp_line
			(start -0.12065 0.3048)
			(end -0.67945 0.3048)
			(stroke
				(width 0.1)
				(type default)
			)
			(layer "F.Fab")
		)
		(fp_line
			(start -0.67945 0.3048)
			(end -0.67945 -0.305054)
			(stroke
				(width 0.1)
				(type default)
			)
			(layer "F.Fab")
		)
		(pad "1" smd circle
			(at -0.40005 0 90)
			(size 0 0)
			(layers "F.Cu" "F.Mask" "F.Paste")
			(net "USB2_5_R1_DN")
		)
		(pad "2" smd circle
			(at 0.40005 0 90)
			(size 0 0)
			(layers "F.Cu" "F.Mask" "F.Paste")
			(net "USB2_5_DN")
		)
	)
	(footprint ""
		(layer "F.Cu")
		(at 15.197582 -410.802836 90)
		(property "Reference" "R2922"
			(at 0 0 90)
			(layer "F.SilkS")
			(hide yes)
			(effects
				(font
					(size 1.27 1.27)
				)
			)
		)
		(property "Value" ""
			(at 0 0 90)
			(layer "F.Fab")
			(effects
				(font
					(size 1.27 1.27)
				)
			)
		)
		(duplicate_pad_numbers_are_jumpers no)
		(fp_line
			(start 0.7874 -0.4064)
			(end 0.7874 0.4064)
			(stroke
				(width 0.1524)
				(type default)
			)
			(layer "F.SilkS")
		)
		(fp_line
			(start -0.7874 -0.4064)
			(end 0.7874 -0.4064)
			(stroke
				(width 0.1524)
				(type default)
			)
			(layer "F.SilkS")
		)
		(fp_line
			(start 0.7874 0.4064)
			(end -0.7874 0.4064)
			(stroke
				(width 0.1524)
				(type default)
			)
			(layer "F.SilkS")
		)
		(fp_line
			(start -0.7874 0.4064)
			(end -0.7874 -0.4064)
			(stroke
				(width 0.1524)
				(type default)
			)
			(layer "F.SilkS")
		)
		(fp_line
			(start -0.12065 -0.305054)
			(end -0.12065 -0.2794)
			(stroke
				(width 0.1)
				(type default)
			)
			(layer "F.Fab")
		)
		(fp_line
			(start -0.67945 -0.305054)
			(end -0.12065 -0.305054)
			(stroke
				(width 0.1)
				(type default)
			)
			(layer "F.Fab")
		)
		(fp_line
			(start 0.67945 -0.3048)
			(end 0.67945 0.3048)
			(stroke
				(width 0.1)
				(type default)
			)
			(layer "F.Fab")
		)
		(fp_line
			(start 0.12065 -0.3048)
			(end 0.67945 -0.3048)
			(stroke
				(width 0.1)
				(type default)
			)
			(layer "F.Fab")
		)
		(fp_line
			(start 0.12065 -0.2794)
			(end 0.12065 -0.3048)
			(stroke
				(width 0.1)
				(type default)
			)
			(layer "F.Fab")
		)
		(fp_line
			(start -0.12065 -0.2794)
			(end 0.12065 -0.2794)
			(stroke
				(width 0.1)
				(type default)
			)
			(layer "F.Fab")
		)
		(fp_line
			(start 0.120396 0.2794)
			(end -0.12065 0.2794)
			(stroke
				(width 0.1)
				(type default)
			)
			(layer "F.Fab")
		)
		(fp_line
			(start -0.12065 0.2794)
			(end -0.12065 0.3048)
			(stroke
				(width 0.1)
				(type default)
			)
			(layer "F.Fab")
		)
		(fp_line
			(start 0.67945 0.3048)
			(end 0.120396 0.3048)
			(stroke
				(width 0.1)
				(type default)
			)
			(layer "F.Fab")
		)
		(fp_line
			(start 0.120396 0.3048)
			(end 0.120396 0.2794)
			(stroke
				(width 0.1)
				(type default)
			)
			(layer "F.Fab")
		)
		(fp_line
			(start -0.12065 0.3048)
			(end -0.67945 0.3048)
			(stroke
				(width 0.1)
				(type default)
			)
			(layer "F.Fab")
		)
		(fp_line
			(start -0.67945 0.3048)
			(end -0.67945 -0.305054)
			(stroke
				(width 0.1)
				(type default)
			)
			(layer "F.Fab")
		)
		(pad "1" smd circle
			(at -0.40005 0 90)
			(size 0 0)
			(layers "F.Cu" "F.Mask" "F.Paste")
			(net "RST_SMB_SWITCH_N")
		)
		(pad "2" smd circle
			(at 0.40005 0 90)
			(size 0 0)
			(layers "F.Cu" "F.Mask" "F.Paste")
			(net "PU_RST_SMB_U181_N")
		)
	)
)
